# S9S_MB_2U (Grand Teton) — schematic netlist excerpt (pin names and nets, part order shuffled) for the footprints in the layout excerpt that follows; sources: Cadence DE-HDL packaged netlist, KiCad conversion of 03242023_DA0F0TMBIJ0_F0T_Motherboard_J_brd_V01_OCP.brd

PC564  Q_CAP  100NF 50V 10% X7R  pkg C0402  page 285 : A = SW_PVCCIN_CPU1_BOOT2_R ; B = SW_PVCCIN_CPU1_BOOTR2
R3496  Q_RES  33.2 1% CHIP  pkg 0402LF  page 150 : A = GPU_FPGA_EROT_RST_BUF_R_N ; B = GPU_FPGA_EROT_RST_BUF_N

(kicad_pcb
	(version 20260206)
	(generator "pcbnew")
	(generator_version "10.0")
	(general
		(thickness 1.6)
		(legacy_teardrops no)
	)
	(paper "A4")
	(title_block
		(title "03242023_DA0F0TMBIJ0_F0T_Motherboard_J_brd_V01_OCP.brd")
		(comment 1 "Grand Teton / footprints 610-611 of 6105")
	)
	(layers
		(0 "F.Cu" signal "TOP")
		(4 "In1.Cu" signal "GND")
		(6 "In2.Cu" signal "IN1")
		(8 "In3.Cu" signal "GND1")
		(10 "In4.Cu" signal "IN2")
		(12 "In5.Cu" signal "GND2")
		(14 "In6.Cu" signal "IN3")
		(16 "In7.Cu" signal "GND3")
		(18 "In8.Cu" signal "VCC")
		(20 "In9.Cu" signal "VCC1")
		(22 "In10.Cu" signal "GND4")
		(24 "In11.Cu" signal "IN4")
		(26 "In12.Cu" signal "GND5")
		(28 "In13.Cu" signal "IN5")
		(30 "In14.Cu" signal "GND6")
		(32 "In15.Cu" signal "IN6")
		(34 "In16.Cu" signal "GND7")
		(2 "B.Cu" signal "BOTTOM")
		(9 "F.Adhes" user "F.Adhesive")
		(11 "B.Adhes" user "B.Adhesive")
		(13 "F.Paste" user "Package Geometry/Pastemask Top")
		(15 "B.Paste" user "Package Geometry/Pastemask Bottom")
		(5 "F.SilkS" user "Ref Des/Silkscreen Top")
		(7 "B.SilkS" user "Ref Des/Silkscreen Bottom")
		(1 "F.Mask" user "Board Geometry/Soldermask Top")
		(3 "B.Mask" user "Board Geometry/Soldermask Bottom")
		(17 "Dwgs.User" user "User.Drawings")
		(19 "Cmts.User" user "User.Comments")
		(21 "Eco1.User" user "User.Eco1")
		(23 "Eco2.User" user "User.Eco2")
		(25 "Edge.Cuts" user "Board Geometry/Outline")
		(27 "Margin" user)
		(31 "F.CrtYd" user "Package Geometry/Place Bound Top")
		(29 "B.CrtYd" user "Package Geometry/Place Bound Bottom")
		(35 "F.Fab" user "Ref Des/Assembly Top")
		(33 "B.Fab" user "Ref Des/Assembly Bottom")
	)
	(footprint ""
		(layer "F.Cu")
		(at 106.990896 -338.180172 -90)
		(property "Reference" "PC564"
			(at 0 0 270)
			(layer "F.SilkS")
			(hide yes)
			(effects
				(font
					(size 1.27 1.27)
				)
			)
		)
		(property "Value" ""
			(at 0 0 270)
			(layer "F.Fab")
			(effects
				(font
					(size 1.27 1.27)
				)
			)
		)
		(duplicate_pad_numbers_are_jumpers no)
		(fp_line
			(start -0.7874 0.4064)
			(end -0.7874 -0.4064)
			(stroke
				(width 0.1524)
				(type default)
			)
			(layer "F.SilkS")
		)
		(fp_line
			(start 0.7874 0.4064)
			(end -0.7874 0.4064)
			(stroke
				(width 0.1524)
				(type default)
			)
			(layer "F.SilkS")
		)
		(fp_line
			(start -0.7874 -0.4064)
			(end 0.7874 -0.4064)
			(stroke
				(width 0.1524)
				(type default)
			)
			(layer "F.SilkS")
		)
		(fp_line
			(start 0.7874 -0.4064)
			(end 0.7874 0.4064)
			(stroke
				(width 0.1524)
				(type default)
			)
			(layer "F.SilkS")
		)
		(fp_line
			(start -0.67945 0.3048)
			(end -0.67945 -0.305054)
			(stroke
				(width 0.1)
				(type default)
			)
			(layer "F.Fab")
		)
		(fp_line
			(start -0.12065 0.3048)
			(end -0.67945 0.3048)
			(stroke
				(width 0.1)
				(type default)
			)
			(layer "F.Fab")
		)
		(fp_line
			(start 0.120396 0.3048)
			(end 0.120396 0.2794)
			(stroke
				(width 0.1)
				(type default)
			)
			(layer "F.Fab")
		)
		(fp_line
			(start 0.67945 0.3048)
			(end 0.120396 0.3048)
			(stroke
				(width 0.1)
				(type default)
			)
			(layer "F.Fab")
		)
		(fp_line
			(start -0.12065 0.2794)
			(end -0.12065 0.3048)
			(stroke
				(width 0.1)
				(type default)
			)
			(layer "F.Fab")
		)
		(fp_line
			(start 0.120396 0.2794)
			(end -0.12065 0.2794)
			(stroke
				(width 0.1)
				(type default)
			)
			(layer "F.Fab")
		)
		(fp_line
			(start -0.12065 -0.2794)
			(end 0.12065 -0.2794)
			(stroke
				(width 0.1)
				(type default)
			)
			(layer "F.Fab")
		)
		(fp_line
			(start 0.12065 -0.2794)
			(end 0.12065 -0.3048)
			(stroke
				(width 0.1)
				(type default)
			)
			(layer "F.Fab")
		)
		(fp_line
			(start 0.12065 -0.3048)
			(end 0.67945 -0.3048)
			(stroke
				(width 0.1)
				(type default)
			)
			(layer "F.Fab")
		)
		(fp_line
			(start 0.67945 -0.3048)
			(end 0.67945 0.3048)
			(stroke
				(width 0.1)
				(type default)
			)
			(layer "F.Fab")
		)
		(fp_line
			(start -0.67945 -0.305054)
			(end -0.12065 -0.305054)
			(stroke
				(width 0.1)
				(type default)
			)
			(layer "F.Fab")
		)
		(fp_line
			(start -0.12065 -0.305054)
			(end -0.12065 -0.2794)
			(stroke
				(width 0.1)
				(type default)
			)
			(layer "F.Fab")
		)
		(pad "1" smd circle
			(at -0.40005 0 270)
			(size 0 0)
			(layers "F.Cu" "F.Mask" "F.Paste")
			(net "SW_PVCCIN_CPU1_BOOT2_R")
		)
		(pad "2" smd circle
			(at 0.40005 0 270)
			(size 0 0)
			(layers "F.Cu" "F.Mask" "F.Paste")
			(net "SW_PVCCIN_CPU1_BOOTR2")
		)
	)
	(footprint ""
		(layer "F.Cu")
		(at 101.833934 -397.46174 180)
		(property "Reference" "R3496"
			(at 0 0 180)
			(layer "F.SilkS")
			(hide yes)
			(effects
				(font
					(size 1.27 1.27)
				)
			)
		)
		(property "Value" ""
			(at 0 0 180)
			(layer "F.Fab")
			(effects
				(font
					(size 1.27 1.27)
				)
			)
		)
		(duplicate_pad_numbers_are_jumpers no)
		(fp_line
			(start 0.7874 0.4064)
			(end -0.7874 0.4064)
			(stroke
				(width 0.1524)
				(type default)
			)
			(layer "F.SilkS")
		)
		(fp_line
			(start 0.7874 -0.4064)
			(end 0.7874 0.4064)
			(stroke
				(width 0.1524)
				(type default)
			)
			(layer "F.SilkS")
		)
		(fp_line
			(start -0.7874 0.4064)
			(end -0.7874 -0.4064)
			(stroke
				(width 0.1524)
				(type default)
			)
			(layer "F.SilkS")
		)
		(fp_line
			(start -0.7874 -0.4064)
			(end 0.7874 -0.4064)
			(stroke
				(width 0.1524)
				(type default)
			)
			(layer "F.SilkS")
		)
		(fp_line
			(start 0.67945 0.3048)
			(end 0.120396 0.3048)
			(stroke
				(width 0.1)
				(type default)
			)
			(layer "F.Fab")
		)
		(fp_line
			(start 0.67945 -0.3048)
			(end 0.67945 0.3048)
			(stroke
				(width 0.1)
				(type default)
			)
			(layer "F.Fab")
		)
		(fp_line
			(start 0.12065 -0.2794)
			(end 0.12065 -0.3048)
			(stroke
				(width 0.1)
				(type default)
			)
			(layer "F.Fab")
		)
		(fp_line
			(start 0.12065 -0.3048)
			(end 0.67945 -0.3048)
			(stroke
				(width 0.1)
				(type default)
			)
			(layer "F.Fab")
		)
		(fp_line
			(start 0.120396 0.3048)
			(end 0.120396 0.2794)
			(stroke
				(width 0.1)
				(type default)
			)
			(layer "F.Fab")
		)
		(fp_line
			(start 0.120396 0.2794)
			(end -0.12065 0.2794)
			(stroke
				(width 0.1)
				(type default)
			)
			(layer "F.Fab")
		)
		(fp_line
			(start -0.12065 0.3048)
			(end -0.67945 0.3048)
			(stroke
				(width 0.1)
				(type default)
			)
			(layer "F.Fab")
		)
		(fp_line
			(start -0.12065 0.2794)
			(end -0.12065 0.3048)
			(stroke
				(width 0.1)
				(type default)
			)
			(layer "F.Fab")
		)
		(fp_line
			(start -0.12065 -0.2794)
			(end 0.12065 -0.2794)
			(stroke
				(width 0.1)
				(type default)
			)
			(layer "F.Fab")
		)
		(fp_line
			(start -0.12065 -0.305054)
			(end -0.12065 -0.2794)
			(stroke
				(width 0.1)
				(type default)
			)
			(layer "F.Fab")
		)
		(fp_line
			(start -0.67945 0.3048)
			(end -0.67945 -0.305054)
			(stroke
				(width 0.1)
				(type default)
			)
			(layer "F.Fab")
		)
		(fp_line
			(start -0.67945 -0.305054)
			(end -0.12065 -0.305054)
			(stroke
				(width 0.1)
				(type default)
			)
			(layer "F.Fab")
		)
		(pad "1" smd circle
			(at -0.40005 0 180)
			(size 0 0)
			(layers "F.Cu" "F.Mask" "F.Paste")
			(net "GPU_FPGA_EROT_RST_BUF_R_N")
		)
		(pad "2" smd circle
			(at 0.40005 0 180)
			(size 0 0)
			(layers "F.Cu" "F.Mask" "F.Paste")
			(net "GPU_FPGA_EROT_RST_BUF_N")
		)
	)
)
